# T6G (Grand Teton) — schematic netlist excerpt (pin names and nets, part order shuffled) for the footprints in the layout excerpt that follows; sources: Cadence DE-HDL packaged netlist, KiCad conversion of 04192023_DAF0TMB3IC0_F0TG_MB_C_brd_V02_OCP.brd

R411  Q_RES  2.2K 5% CHIP  pkg 0402LF  page 27 : A = CPU0_BP3 ; B = PVDD18_S5_P0
R991  Q_RES  0 5% EMPTY  pkg 0402LF  page 159 : A = I3C_1_SPD_DDRGL_CPU1_R_SDA ; B = I3C_SPD_DDRGL_CPU1_BYPASS_SDA
PC128_4  Q_CAP  22UF 4V 20% X6S  pkg C0805  page 202 : A = PVDDCR_CPU1_P0 ; B = GND

(kicad_pcb
	(version 20260206)
	(generator "pcbnew")
	(generator_version "10.0")
	(general
		(thickness 1.6)
		(legacy_teardrops no)
	)
	(paper "A4")
	(title_block
		(title "04192023_DAF0TMB3IC0_F0TG_MB_C_brd_V02_OCP.brd")
		(comment 1 "Grand Teton / footprints 6693-6695 of 8354")
	)
	(layers
		(0 "F.Cu" signal "TOP")
		(4 "In1.Cu" signal "GND")
		(6 "In2.Cu" signal "IN1")
		(8 "In3.Cu" signal "GND1")
		(10 "In4.Cu" signal "IN2")
		(12 "In5.Cu" signal "GND2")
		(14 "In6.Cu" signal "IN3")
		(16 "In7.Cu" signal "GND3")
		(18 "In8.Cu" signal "VCC")
		(20 "In9.Cu" signal "VCC1")
		(22 "In10.Cu" signal "GND4")
		(24 "In11.Cu" signal "IN4")
		(26 "In12.Cu" signal "GND5")
		(28 "In13.Cu" signal "IN5")
		(30 "In14.Cu" signal "GND6")
		(32 "In15.Cu" signal "IN6")
		(34 "In16.Cu" signal "GND7")
		(2 "B.Cu" signal "BOTTOM")
		(9 "F.Adhes" user "F.Adhesive")
		(11 "B.Adhes" user "B.Adhesive")
		(13 "F.Paste" user "Package Geometry/Pastemask Top")
		(15 "B.Paste" user "Package Geometry/Pastemask Bottom")
		(5 "F.SilkS" user "Ref Des/Silkscreen Top")
		(7 "B.SilkS" user "Ref Des/Silkscreen Bottom")
		(1 "F.Mask" user "Board Geometry/Soldermask Top")
		(3 "B.Mask" user "Board Geometry/Soldermask Bottom")
		(17 "Dwgs.User" user "User.Drawings")
		(19 "Cmts.User" user "User.Comments")
		(21 "Eco1.User" user "User.Eco1")
		(23 "Eco2.User" user "User.Eco2")
		(25 "Edge.Cuts" user "Board Geometry/Outline")
		(27 "Margin" user)
		(31 "F.CrtYd" user "Package Geometry/Place Bound Top")
		(29 "B.CrtYd" user "Package Geometry/Place Bound Bottom")
		(35 "F.Fab" user "Ref Des/Assembly Top")
		(33 "B.Fab" user "Ref Des/Assembly Bottom")
	)
	(footprint ""
		(layer "B.Cu")
		(at 307.500528 -338.082128 -90)
		(property "Reference" "PC128_4"
			(at 0 0 90)
			(layer "B.SilkS")
			(hide yes)
			(effects
				(font
					(size 1.27 1.27)
				)
				(justify mirror)
			)
		)
		(property "Value" ""
			(at 0 0 90)
			(layer "B.Fab")
			(effects
				(font
					(size 1.27 1.27)
				)
				(justify mirror)
			)
		)
		(duplicate_pad_numbers_are_jumpers no)
		(fp_line
			(start -1.524 0.762)
			(end 1.524 0.762)
			(stroke
				(width 0.1524)
				(type default)
			)
			(layer "B.SilkS")
		)
		(fp_line
			(start 1.524 0.762)
			(end 1.524 -0.762)
			(stroke
				(width 0.1524)
				(type default)
			)
			(layer "B.SilkS")
		)
		(fp_line
			(start -1.524 -0.762)
			(end -1.524 0.762)
			(stroke
				(width 0.1524)
				(type default)
			)
			(layer "B.SilkS")
		)
		(fp_line
			(start 1.524 -0.762)
			(end -1.524 -0.762)
			(stroke
				(width 0.1524)
				(type default)
			)
			(layer "B.SilkS")
		)
		(fp_line
			(start -1.1049 0.724916)
			(end -1.1049 -0.724916)
			(stroke
				(width 0.1)
				(type default)
			)
			(layer "B.Fab")
		)
		(fp_line
			(start 1.1049 0.724916)
			(end -1.1049 0.724916)
			(stroke
				(width 0.1)
				(type default)
			)
			(layer "B.Fab")
		)
		(fp_line
			(start -1.1049 -0.724916)
			(end 1.1049 -0.724916)
			(stroke
				(width 0.1)
				(type default)
			)
			(layer "B.Fab")
		)
		(fp_line
			(start 1.1049 -0.724916)
			(end 1.1049 0.724916)
			(stroke
				(width 0.1)
				(type default)
			)
			(layer "B.Fab")
		)
		(pad "1" smd rect
			(at 0.889 0 270)
			(size 1.016 1.27)
			(layers "B.Cu" "B.Mask" "B.Paste")
			(net "PVDDCR_CPU1_P0")
		)
		(pad "2" smd rect
			(at -0.889 0 270)
			(size 1.016 1.27)
			(layers "B.Cu" "B.Mask" "B.Paste")
			(net "GND")
		)
	)
	(footprint ""
		(layer "B.Cu")
		(at 322.878958 -195.662296)
		(property "Reference" "R411"
			(at 0 0 0)
			(layer "B.SilkS")
			(hide yes)
			(effects
				(font
					(size 1.27 1.27)
				)
				(justify mirror)
			)
		)
		(property "Value" ""
			(at 0 0 0)
			(layer "B.Fab")
			(effects
				(font
					(size 1.27 1.27)
				)
				(justify mirror)
			)
		)
		(duplicate_pad_numbers_are_jumpers no)
		(fp_line
			(start -0.7874 -0.4064)
			(end -0.7874 0.4064)
			(stroke
				(width 0.1524)
				(type default)
			)
			(layer "B.SilkS")
		)
		(fp_line
			(start -0.7874 0.4064)
			(end 0.7874 0.4064)
			(stroke
				(width 0.1524)
				(type default)
			)
			(layer "B.SilkS")
		)
		(fp_line
			(start 0.7874 -0.4064)
			(end -0.7874 -0.4064)
			(stroke
				(width 0.1524)
				(type default)
			)
			(layer "B.SilkS")
		)
		(fp_line
			(start 0.7874 0.4064)
			(end 0.7874 -0.4064)
			(stroke
				(width 0.1524)
				(type default)
			)
			(layer "B.SilkS")
		)
		(fp_line
			(start -0.67945 -0.3048)
			(end -0.67945 0.3048)
			(stroke
				(width 0.1)
				(type default)
			)
			(layer "B.Fab")
		)
		(fp_line
			(start -0.67945 0.3048)
			(end -0.120396 0.3048)
			(stroke
				(width 0.1)
				(type default)
			)
			(layer "B.Fab")
		)
		(fp_line
			(start -0.12065 -0.3048)
			(end -0.67945 -0.3048)
			(stroke
				(width 0.1)
				(type default)
			)
			(layer "B.Fab")
		)
		(fp_line
			(start -0.12065 -0.2794)
			(end -0.12065 -0.3048)
			(stroke
				(width 0.1)
				(type default)
			)
			(layer "B.Fab")
		)
		(fp_line
			(start -0.120396 0.2794)
			(end 0.12065 0.2794)
			(stroke
				(width 0.1)
				(type default)
			)
			(layer "B.Fab")
		)
		(fp_line
			(start -0.120396 0.3048)
			(end -0.120396 0.2794)
			(stroke
				(width 0.1)
				(type default)
			)
			(layer "B.Fab")
		)
		(fp_line
			(start 0.12065 -0.305054)
			(end 0.12065 -0.2794)
			(stroke
				(width 0.1)
				(type default)
			)
			(layer "B.Fab")
		)
		(fp_line
			(start 0.12065 -0.2794)
			(end -0.12065 -0.2794)
			(stroke
				(width 0.1)
				(type default)
			)
			(layer "B.Fab")
		)
		(fp_line
			(start 0.12065 0.2794)
			(end 0.12065 0.3048)
			(stroke
				(width 0.1)
				(type default)
			)
			(layer "B.Fab")
		)
		(fp_line
			(start 0.12065 0.3048)
			(end 0.67945 0.3048)
			(stroke
				(width 0.1)
				(type default)
			)
			(layer "B.Fab")
		)
		(fp_line
			(start 0.67945 -0.305054)
			(end 0.12065 -0.305054)
			(stroke
				(width 0.1)
				(type default)
			)
			(layer "B.Fab")
		)
		(fp_line
			(start 0.67945 0.3048)
			(end 0.67945 -0.305054)
			(stroke
				(width 0.1)
				(type default)
			)
			(layer "B.Fab")
		)
		(pad "1" smd circle
			(at 0.40005 0 180)
			(size 0 0)
			(layers "B.Cu" "B.Mask" "B.Paste")
			(net "CPU0_BP3")
		)
		(pad "2" smd circle
			(at -0.40005 0 180)
			(size 0 0)
			(layers "B.Cu" "B.Mask" "B.Paste")
			(net "PVDD18_S5_P0")
		)
	)
	(footprint ""
		(layer "B.Cu")
		(at 161.276284 -193.707512 -90)
		(property "Reference" "R991"
			(at 0 0 90)
			(layer "B.SilkS")
			(hide yes)
			(effects
				(font
					(size 1.27 1.27)
				)
				(justify mirror)
			)
		)
		(property "Value" ""
			(at 0 0 90)
			(layer "B.Fab")
			(effects
				(font
					(size 1.27 1.27)
				)
				(justify mirror)
			)
		)
		(duplicate_pad_numbers_are_jumpers no)
		(fp_line
			(start -0.7874 0.4064)
			(end 0.7874 0.4064)
			(stroke
				(width 0.1524)
				(type default)
			)
			(layer "B.SilkS")
		)
		(fp_line
			(start 0.7874 0.4064)
			(end 0.7874 -0.4064)
			(stroke
				(width 0.1524)
				(type default)
			)
			(layer "B.SilkS")
		)
		(fp_line
			(start -0.7874 -0.4064)
			(end -0.7874 0.4064)
			(stroke
				(width 0.1524)
				(type default)
			)
			(layer "B.SilkS")
		)
		(fp_line
			(start 0.7874 -0.4064)
			(end -0.7874 -0.4064)
			(stroke
				(width 0.1524)
				(type default)
			)
			(layer "B.SilkS")
		)
		(fp_line
			(start -0.67945 0.3048)
			(end -0.120396 0.3048)
			(stroke
				(width 0.1)
				(type default)
			)
			(layer "B.Fab")
		)
		(fp_line
			(start -0.120396 0.3048)
			(end -0.120396 0.2794)
			(stroke
				(width 0.1)
				(type default)
			)
			(layer "B.Fab")
		)
		(fp_line
			(start 0.12065 0.3048)
			(end 0.67945 0.3048)
			(stroke
				(width 0.1)
				(type default)
			)
			(layer "B.Fab")
		)
		(fp_line
			(start 0.67945 0.3048)
			(end 0.67945 -0.305054)
			(stroke
				(width 0.1)
				(type default)
			)
			(layer "B.Fab")
		)
		(fp_line
			(start -0.120396 0.2794)
			(end 0.12065 0.2794)
			(stroke
				(width 0.1)
				(type default)
			)
			(layer "B.Fab")
		)
		(fp_line
			(start 0.12065 0.2794)
			(end 0.12065 0.3048)
			(stroke
				(width 0.1)
				(type default)
			)
			(layer "B.Fab")
		)
		(fp_line
			(start -0.12065 -0.2794)
			(end -0.12065 -0.3048)
			(stroke
				(width 0.1)
				(type default)
			)
			(layer "B.Fab")
		)
		(fp_line
			(start 0.12065 -0.2794)
			(end -0.12065 -0.2794)
			(stroke
				(width 0.1)
				(type default)
			)
			(layer "B.Fab")
		)
		(fp_line
			(start -0.67945 -0.3048)
			(end -0.67945 0.3048)
			(stroke
				(width 0.1)
				(type default)
			)
			(layer "B.Fab")
		)
		(fp_line
			(start -0.12065 -0.3048)
			(end -0.67945 -0.3048)
			(stroke
				(width 0.1)
				(type default)
			)
			(layer "B.Fab")
		)
		(fp_line
			(start 0.12065 -0.305054)
			(end 0.12065 -0.2794)
			(stroke
				(width 0.1)
				(type default)
			)
			(layer "B.Fab")
		)
		(fp_line
			(start 0.67945 -0.305054)
			(end 0.12065 -0.305054)
			(stroke
				(width 0.1)
				(type default)
			)
			(layer "B.Fab")
		)
		(pad "1" smd rect
			(at 0.40005 0 270)
			(size 0.4572 0.508)
			(layers "B.Cu" "B.Mask" "B.Paste")
			(net "I3C_1_SPD_DDRGL_CPU1_R_SDA")
		)
		(pad "2" smd rect
			(at -0.40005 0 270)
			(size 0.4572 0.508)
			(layers "B.Cu" "B.Mask" "B.Paste")
			(net "I3C_SPD_DDRGL_CPU1_BYPASS_SDA")
		)
	)
)
